# T6G (Grand Teton) — schematic netlist excerpt (pin names and nets, part order shuffled) for the footprints in the layout excerpt that follows; sources: Cadence DE-HDL packaged netlist, KiCad conversion of 04192023_DAF0TMB3IC0_F0TG_MB_C_brd_V02_OCP.brd

R3395  Q_RES  2.2K 5% CHIP  pkg 0402LF  page 250 : A = P3V3_AUX ; B = SMB_INA230_3V3AUX_SCL
PR3944  Q_RES  46.4K 1% CHIP  pkg 0402LF  page 147 : A = P12V_E1S_ISET_0 ; B = GND

(kicad_pcb
	(version 20260206)
	(generator "pcbnew")
	(generator_version "10.0")
	(general
		(thickness 1.6)
		(legacy_teardrops no)
	)
	(paper "A4")
	(title_block
		(title "04192023_DAF0TMB3IC0_F0TG_MB_C_brd_V02_OCP.brd")
		(comment 1 "Grand Teton / footprints 2168-2169 of 8354")
	)
	(layers
		(0 "F.Cu" signal "TOP")
		(4 "In1.Cu" signal "GND")
		(6 "In2.Cu" signal "IN1")
		(8 "In3.Cu" signal "GND1")
		(10 "In4.Cu" signal "IN2")
		(12 "In5.Cu" signal "GND2")
		(14 "In6.Cu" signal "IN3")
		(16 "In7.Cu" signal "GND3")
		(18 "In8.Cu" signal "VCC")
		(20 "In9.Cu" signal "VCC1")
		(22 "In10.Cu" signal "GND4")
		(24 "In11.Cu" signal "IN4")
		(26 "In12.Cu" signal "GND5")
		(28 "In13.Cu" signal "IN5")
		(30 "In14.Cu" signal "GND6")
		(32 "In15.Cu" signal "IN6")
		(34 "In16.Cu" signal "GND7")
		(2 "B.Cu" signal "BOTTOM")
		(9 "F.Adhes" user "F.Adhesive")
		(11 "B.Adhes" user "B.Adhesive")
		(13 "F.Paste" user "Package Geometry/Pastemask Top")
		(15 "B.Paste" user "Package Geometry/Pastemask Bottom")
		(5 "F.SilkS" user "Ref Des/Silkscreen Top")
		(7 "B.SilkS" user "Ref Des/Silkscreen Bottom")
		(1 "F.Mask" user "Board Geometry/Soldermask Top")
		(3 "B.Mask" user "Board Geometry/Soldermask Bottom")
		(17 "Dwgs.User" user "User.Drawings")
		(19 "Cmts.User" user "User.Comments")
		(21 "Eco1.User" user "User.Eco1")
		(23 "Eco2.User" user "User.Eco2")
		(25 "Edge.Cuts" user "Board Geometry/Outline")
		(27 "Margin" user)
		(31 "F.CrtYd" user "Package Geometry/Place Bound Top")
		(29 "B.CrtYd" user "Package Geometry/Place Bound Bottom")
		(35 "F.Fab" user "Ref Des/Assembly Top")
		(33 "B.Fab" user "Ref Des/Assembly Bottom")
	)
	(footprint ""
		(layer "F.Cu")
		(at 297.486324 -119.339614 180)
		(property "Reference" "R3395"
			(at 0 0 180)
			(layer "F.SilkS")
			(hide yes)
			(effects
				(font
					(size 1.27 1.27)
				)
			)
		)
		(property "Value" ""
			(at 0 0 180)
			(layer "F.Fab")
			(effects
				(font
					(size 1.27 1.27)
				)
			)
		)
		(duplicate_pad_numbers_are_jumpers no)
		(fp_line
			(start 0.7874 0.4064)
			(end -0.7874 0.4064)
			(stroke
				(width 0.1524)
				(type default)
			)
			(layer "F.SilkS")
		)
		(fp_line
			(start 0.7874 -0.4064)
			(end 0.7874 0.4064)
			(stroke
				(width 0.1524)
				(type default)
			)
			(layer "F.SilkS")
		)
		(fp_line
			(start -0.7874 0.4064)
			(end -0.7874 -0.4064)
			(stroke
				(width 0.1524)
				(type default)
			)
			(layer "F.SilkS")
		)
		(fp_line
			(start -0.7874 -0.4064)
			(end 0.7874 -0.4064)
			(stroke
				(width 0.1524)
				(type default)
			)
			(layer "F.SilkS")
		)
		(fp_line
			(start 0.67945 0.3048)
			(end 0.120396 0.3048)
			(stroke
				(width 0.1)
				(type default)
			)
			(layer "F.Fab")
		)
		(fp_line
			(start 0.67945 -0.3048)
			(end 0.67945 0.3048)
			(stroke
				(width 0.1)
				(type default)
			)
			(layer "F.Fab")
		)
		(fp_line
			(start 0.12065 -0.2794)
			(end 0.12065 -0.3048)
			(stroke
				(width 0.1)
				(type default)
			)
			(layer "F.Fab")
		)
		(fp_line
			(start 0.12065 -0.3048)
			(end 0.67945 -0.3048)
			(stroke
				(width 0.1)
				(type default)
			)
			(layer "F.Fab")
		)
		(fp_line
			(start 0.120396 0.3048)
			(end 0.120396 0.2794)
			(stroke
				(width 0.1)
				(type default)
			)
			(layer "F.Fab")
		)
		(fp_line
			(start 0.120396 0.2794)
			(end -0.12065 0.2794)
			(stroke
				(width 0.1)
				(type default)
			)
			(layer "F.Fab")
		)
		(fp_line
			(start -0.12065 0.3048)
			(end -0.67945 0.3048)
			(stroke
				(width 0.1)
				(type default)
			)
			(layer "F.Fab")
		)
		(fp_line
			(start -0.12065 0.2794)
			(end -0.12065 0.3048)
			(stroke
				(width 0.1)
				(type default)
			)
			(layer "F.Fab")
		)
		(fp_line
			(start -0.12065 -0.2794)
			(end 0.12065 -0.2794)
			(stroke
				(width 0.1)
				(type default)
			)
			(layer "F.Fab")
		)
		(fp_line
			(start -0.12065 -0.305054)
			(end -0.12065 -0.2794)
			(stroke
				(width 0.1)
				(type default)
			)
			(layer "F.Fab")
		)
		(fp_line
			(start -0.67945 0.3048)
			(end -0.67945 -0.305054)
			(stroke
				(width 0.1)
				(type default)
			)
			(layer "F.Fab")
		)
		(fp_line
			(start -0.67945 -0.305054)
			(end -0.12065 -0.305054)
			(stroke
				(width 0.1)
				(type default)
			)
			(layer "F.Fab")
		)
		(pad "1" smd circle
			(at -0.40005 0 180)
			(size 0 0)
			(layers "F.Cu" "F.Mask" "F.Paste")
			(net "P3V3_AUX")
		)
		(pad "2" smd circle
			(at 0.40005 0 180)
			(size 0 0)
			(layers "F.Cu" "F.Mask" "F.Paste")
			(net "SMB_INA230_3V3AUX_SCL")
		)
	)
	(footprint ""
		(layer "F.Cu")
		(at 257.84048 -51.587146)
		(property "Reference" "PR3944"
			(at 0 0 0)
			(layer "F.SilkS")
			(hide yes)
			(effects
				(font
					(size 1.27 1.27)
				)
			)
		)
		(property "Value" ""
			(at 0 0 0)
			(layer "F.Fab")
			(effects
				(font
					(size 1.27 1.27)
				)
			)
		)
		(duplicate_pad_numbers_are_jumpers no)
		(fp_line
			(start -0.7874 -0.4064)
			(end 0.7874 -0.4064)
			(stroke
				(width 0.1524)
				(type default)
			)
			(layer "F.SilkS")
		)
		(fp_line
			(start -0.7874 0.4064)
			(end -0.7874 -0.4064)
			(stroke
				(width 0.1524)
				(type default)
			)
			(layer "F.SilkS")
		)
		(fp_line
			(start 0.7874 -0.4064)
			(end 0.7874 0.4064)
			(stroke
				(width 0.1524)
				(type default)
			)
			(layer "F.SilkS")
		)
		(fp_line
			(start 0.7874 0.4064)
			(end -0.7874 0.4064)
			(stroke
				(width 0.1524)
				(type default)
			)
			(layer "F.SilkS")
		)
		(fp_line
			(start -0.67945 -0.305054)
			(end -0.12065 -0.305054)
			(stroke
				(width 0.1)
				(type default)
			)
			(layer "F.Fab")
		)
		(fp_line
			(start -0.67945 0.3048)
			(end -0.67945 -0.305054)
			(stroke
				(width 0.1)
				(type default)
			)
			(layer "F.Fab")
		)
		(fp_line
			(start -0.12065 -0.305054)
			(end -0.12065 -0.2794)
			(stroke
				(width 0.1)
				(type default)
			)
			(layer "F.Fab")
		)
		(fp_line
			(start -0.12065 -0.2794)
			(end 0.12065 -0.2794)
			(stroke
				(width 0.1)
				(type default)
			)
			(layer "F.Fab")
		)
		(fp_line
			(start -0.12065 0.2794)
			(end -0.12065 0.3048)
			(stroke
				(width 0.1)
				(type default)
			)
			(layer "F.Fab")
		)
		(fp_line
			(start -0.12065 0.3048)
			(end -0.67945 0.3048)
			(stroke
				(width 0.1)
				(type default)
			)
			(layer "F.Fab")
		)
		(fp_line
			(start 0.120396 0.2794)
			(end -0.12065 0.2794)
			(stroke
				(width 0.1)
				(type default)
			)
			(layer "F.Fab")
		)
		(fp_line
			(start 0.120396 0.3048)
			(end 0.120396 0.2794)
			(stroke
				(width 0.1)
				(type default)
			)
			(layer "F.Fab")
		)
		(fp_line
			(start 0.12065 -0.3048)
			(end 0.67945 -0.3048)
			(stroke
				(width 0.1)
				(type default)
			)
			(layer "F.Fab")
		)
		(fp_line
			(start 0.12065 -0.2794)
			(end 0.12065 -0.3048)
			(stroke
				(width 0.1)
				(type default)
			)
			(layer "F.Fab")
		)
		(fp_line
			(start 0.67945 -0.3048)
			(end 0.67945 0.3048)
			(stroke
				(width 0.1)
				(type default)
			)
			(layer "F.Fab")
		)
		(fp_line
			(start 0.67945 0.3048)
			(end 0.120396 0.3048)
			(stroke
				(width 0.1)
				(type default)
			)
			(layer "F.Fab")
		)
		(pad "1" smd circle
			(at -0.40005 0)
			(size 0 0)
			(layers "F.Cu" "F.Mask" "F.Paste")
			(net "P12V_E1S_ISET_0")
		)
		(pad "2" smd circle
			(at 0.40005 0)
			(size 0 0)
			(layers "F.Cu" "F.Mask" "F.Paste")
			(net "GND")
		)
	)
)
